G04*
G04 #@! TF.GenerationSoftware,Altium Limited,Altium Designer,23.6.0 (18)*
G04*
G04 Layer_Color=0*
%FSLAX44Y44*%
%MOMM*%
G71*
G04*
G04 #@! TF.SameCoordinates,0D6CC9A4-690D-4EF8-AA6E-9FB67146BD04*
G04*
G04*
G04 #@! TF.FilePolarity,Positive*
G04*
G01*
G75*
%ADD102C,0.0254*%
D102*
X5000Y0D02*
G02*
X0Y5000I0J5000D01*
G01*
Y503013D01*
D02*
G02*
X5000Y508013I5000J0D01*
G01*
Y508000D01*
X503000Y508000D01*
D02*
G02*
X508000Y503000I0J-5000D01*
G01*
X508000Y5000D01*
D02*
G02*
X503000Y0I-5000J-0D01*
G01*
X5000D01*
M02*
